# OCXO_DaughterCard_RakonROD2522.xlsx — OCXO_DaughterCard_RakonROD2522 (bom)
| Comment | Description | Designator | Footprint | LibRef | Quantity |
| Yageo_RC0402FR-07100RL | RES SMD 100 OHM 1% 1/16W 0402 | R5 | RESC1005X040N | RES-CMP-00538-3 | 1 |
| Yageo_RC0201JR-070RL | RES, 0.0 OHM, 0.5A, 1/20W, 0201 | R33 | RESC0603X026N | CMP-RES-00843-1 | 1 |
| Yageo_RC0201FR-0710KL | RES, 10K OHM, 1%, 1/20W, 200PPM/C, 0201 | R34 | RESC0603X026N | CMP-RES-00602-1 | 1 |
| Yageo_CC0402KRX7R7BB103 | CAP, CER, X7R, 0.01UF, 10%, 16V, 0402, 0.55MM T | C12, C14 | CAPC1005X055N | CAP-CMP-00257-3 | 2 |
| Wurth_9774040243R | STANDOFF, ROUND, M2X0.4 STEEL 4MM, 9774040243R | J1, J2 | TH000V_300DIAx400_001mt_9774040243R | CON-CMP-00164-1 | 2 |
| TI_DS90LV028AQMA/NOPB | IC, RVCR, DS90LV028AQ-Q1, DUAL, DIFF, LVDS, 400MBPS, SOIC-8 | U4 | SOP127P600X175_8N | INT-CMP-00017-4 | 1 |
| TI_DS90LV027AQMA/NOPB | IC, DRIVER, DS90LV027AQ, DUAL, DIFF, LVDS, 600MBPS, SOIC-8 | U3 | SOP127P600X175_8N | INT-CMP-00018-2 | 1 |
| TDK_MPZ1608S601ATA00 | FERRITE BEAD, 600 OHM @100MHZ, 25%, 1A, 0.150 OHM DCR, 0603, 0.95MM T | FL1, FL2 | INDC1608X095N | FER-CMP-00057-5 | 2 |
| Stackpole Electronics, Inc._RMCF1210ZT0R00 | RES, 0.0 OHM, 3A, 1/2W, 1210 | R1 | RESC3225X070N | RES-CMP-00829-3 | 1 |
| Stackpole Electronics, Inc._HCJ0402ZT0R00 | RES, 0.0 OHM, 1/8W, 6.5A, 0402 | R6, R7, R8 | RESC1005X045N | RES-CMP-00382-3 | 3 |
| Samtec_HTSW-102-07-T-S | CONN, PIN, HEADER, 2POS, 2.54MM PITCH, 8.38MM H, VERT, TIN, TH | P9 | TH002_254_508x254x838_000mt_HTSW | CON-CMP-00061-3 | 1 |
| Samsung Electro-Mechanics_CL05B104JO5NNNC | CAP, CER, X7R, 0.1UF, 5%, 16V, 0402, 0.55MM T | C1, C6, C7, C9, C11, C13, C17, C19, C21, C23 | CAPC1005X055N | CAP-CMP-00271-3, CMP-CAP-00082-2 | 10 |
| Rakon_ROD2522S2 | OSC, OCXO, 10MHZ - 20MHZ, 0.5PPB STAB, 3.3V, 22.0X25.4X12.3MM, SMT | Y1 | OSC007_762_2540x2200x1230 | COR-CMP-00010-2 | 1 |
| Panasonic_ERJ-2RKF1003X | RES, 100K OHM, 1%, 1/10W, 100PPM/C, 0402 | R4 | RESC1005X040N | RES-CMP-00289-3 | 1 |
| NXP_PCT2075TP,147 | SENSOR DIGITAL -55C-125C 8HWSON | U5 | SON50P300X200X80-HS-9N_EP160x160_IPC | SNS-CMP-00004-1 | 1 |
| Murata_GRM188R61A106ME69D | CAP, CER, X5R, 10UF, 20%, 10V, 0603, 0.80MM T | C22 | CAPC1608X090N | CMP-CAP-00380-1 | 1 |
| Murata_GRM188D71A106MA73D | CAP, CER, X7T, 10UF, 20%, 10V, 0603, 1.00MM T | C8, C10, C18, C20 | CAPC1608X100N | CAP-CMP-00449-3 | 4 |
| Murata_GRM21BR61A226ME51L | CAP, CER, X5R, 22UF, 20%, 10V, 0805, 1.40MM T | C2, C3, C4 | CAPC2013X140N | CAP-CMP-00519-3 | 3 |
| Molex_539160208 | CONN, B2B/FPC, HEADER, 20-POS, 0.5MM PITCH, 4.0MM H, VERT, GOLD, SMT | P10 | SM020V_50_730x310x337_000mt_53916 | CON-CMP-00163-2 | 1 |
| Mill-Max_8600-0-05-80-00-00-03-0 | CONN, PC PIN, PRESS-FIT, 10.16MM LENGTH, TIN, TH | P1, P2, P3, P4, P5, P6, P7, P8, P11, P12 | TH001V_109DIA_000mt_8600-0 | CON-CMP-00162-1 | 10 |
| Microchip_AT24MAC602-XHM-B | IC, EEPROM, AT24MAC602, 2K-BIT (256 X 8), 1MHZ, I2C, 1.7V - 5.5V, TSSOP-8 | U2 | TSSOP65P640X120-8N | MEM-CMP-00010-1 | 1 |
| LMS1587IS-3.3/NOPB | 3A Low Dropout Fast Response Regulators, 3-pin TO-263, Pb-Free | U1 | KTT0003B_L | CMP-0062-00189-5 | 1 |
| Kemet_T491B476K010AT | CAP TANT 47UF 10% 10V 1411 | C5, C15, C16 | CAPMP3528X210N_T520 | CAP-CMP-00042-1 | 3 |
| 4871 | Round Standoff Threaded #2-56 Steel 0.063" (1.60mm) 1/16" | P13, P14, P15, P16 | Keystone_4871 | Keystone_4871 | 4 |
| 4.7K_1%_0402 | Chip Resistor, 4.7 KOhm, +/- 1%, 0.1 W, -55 to 155 degC, 0402 (1005 Metric), RoHS, Tape and Reel | R27, R28, R35, R36 | RESC1005X40X25LL05T05 | CMP-2002-01154-4 | 4 |
| 0_5%_0603 | Chip Resistor, 0 Ohm, +/- 5%, 0.1 W, -55 to 155 degC, 0603 (1608 Metric), RoHS, Tape and Reel | R16, R23 | RESC1608X55X25ML10T15 | CMP-2100-03667-1 | 2 |
| 0_1%_0402 |  | R11, R12, R17, R18, R19, R24, R25, R26, R30, R32 | RESC1005X40X25NL05T10 | CMP-1011-00001-2 | 10 |
